(kicad_pcb
	(version 20260206)
	(generator "pcbnew")
	(generator_version "10.0")
	(general
		(thickness 1.6)
		(legacy_teardrops no)
	)
	(paper "A4")
	(title_block
		(title "v1-pdb — T6M_PDB_D_0927_0900.brd")
		(comment 1 "Open CloudServer (Microsoft) / footprint 310 of 321 (J17), pads 1-46 of 46")
	)
	(layers
		(0 "F.Cu" signal "TOP")
		(4 "In1.Cu" signal "GND")
		(6 "In2.Cu" signal "IN1")
		(8 "In3.Cu" signal "VCC")
		(10 "In4.Cu" signal "VCC1")
		(12 "In5.Cu" signal "IN2")
		(14 "In6.Cu" signal "GND1")
		(2 "B.Cu" signal "BOTTOM")
		(9 "F.Adhes" user "F.Adhesive")
		(11 "B.Adhes" user "B.Adhesive")
		(13 "F.Paste" user "Package Geometry/Pastemask Top")
		(15 "B.Paste" user "Package Geometry/Pastemask Bottom")
		(5 "F.SilkS" user "Ref Des/Silkscreen Top")
		(7 "B.SilkS" user "Ref Des/Silkscreen Bottom")
		(1 "F.Mask" user "Board Geometry/Soldermask Top")
		(3 "B.Mask" user "Board Geometry/Soldermask Bottom")
		(17 "Dwgs.User" user "User.Drawings")
		(19 "Cmts.User" user "User.Comments")
		(21 "Eco1.User" user "User.Eco1")
		(23 "Eco2.User" user "User.Eco2")
		(25 "Edge.Cuts" user "Board Geometry/Outline")
		(27 "Margin" user)
		(31 "F.CrtYd" user "Package Geometry/Place Bound Top")
		(29 "B.CrtYd" user "Package Geometry/Place Bound Bottom")
		(35 "F.Fab" user "Ref Des/Assembly Top")
		(33 "B.Fab" user "Ref Des/Assembly Bottom")
	)
	(footprint ""
		(layer "B.Cu")
		(at 44.03979 -452.76008 90)
		(property "Reference" "J17"
			(at 6.342888 1.323848 0)
			(unlocked yes)
			(layer "B.SilkS")
			(effects
				(font
					(size 0.7874 0.5842)
					(thickness 0.1524)
				)
				(justify left mirror)
			)
		)
		(property "Value" ""
			(at 0 0 90)
			(layer "B.Fab")
			(effects
				(font
					(size 1.27 1.27)
				)
				(justify mirror)
			)
		)
		(duplicate_pad_numbers_are_jumpers no)
		(pad "" np_thru_hole circle
			(at -1.35001 -2.54)
			(size 2.5146 2.5146)
			(drill 2.5146)
			(layers "*.Cu" "*.Mask")
			(clearance 0.381)
			(thermal_gap 0.381)
		)
		(pad "" np_thru_hole circle
			(at 0 50.8)
			(size 2.5146 2.5146)
			(drill 2.5146)
			(layers "*.Cu" "*.Mask")
			(clearance 0.381)
			(thermal_gap 0.381)
		)
		(pad "P1" thru_hole rect
			(at 0 0)
			(size 1.1684 1.1684)
			(drill 0.762)
			(layers "*.Cu" "*.Mask")
			(remove_unused_layers no)
			(net "GND")
			(clearance 0.0508)
			(padstack
				(mode front_inner_back)
				(layer "Inner"
					(shape circle)
					(size 1.1684 1.1684)
					(clearance 0.0508)
				)
				(layer "B.Cu"
					(shape rect)
					(size 1.1684 1.1684)
					(thermal_gap 0.0508)
					(clearance 0.0508)
				)
			)
		)
		(pad "P2" thru_hole circle
			(at 0 2.54)
			(size 1.1684 1.1684)
			(drill 0.762)
			(layers "*.Cu" "*.Mask")
			(remove_unused_layers no)
			(net "GND")
			(clearance 0.0508)
			(thermal_gap 0.0508)
		)
		(pad "P3" thru_hole circle
			(at 0 5.08)
			(size 1.1684 1.1684)
			(drill 0.762)
			(layers "*.Cu" "*.Mask")
			(remove_unused_layers no)
			(net "GND")
			(clearance 0.0508)
			(thermal_gap 0.0508)
		)
		(pad "P4" thru_hole circle
			(at 0 7.62)
			(size 1.1684 1.1684)
			(drill 0.762)
			(layers "*.Cu" "*.Mask")
			(remove_unused_layers no)
			(net "GND")
			(clearance 0.0508)
			(thermal_gap 0.0508)
		)
		(pad "P5" thru_hole circle
			(at 0 10.16)
			(size 1.1684 1.1684)
			(drill 0.762)
			(layers "*.Cu" "*.Mask")
			(remove_unused_layers no)
			(net "GND")
			(clearance 0.0508)
			(thermal_gap 0.0508)
		)
		(pad "P6" thru_hole circle
			(at 0 12.7)
			(size 1.1684 1.1684)
			(drill 0.762)
			(layers "*.Cu" "*.Mask")
			(remove_unused_layers no)
			(net "GND")
			(clearance 0.0508)
			(thermal_gap 0.0508)
		)
		(pad "P7" thru_hole circle
			(at 0 15.24)
			(size 1.1684 1.1684)
			(drill 0.762)
			(layers "*.Cu" "*.Mask")
			(remove_unused_layers no)
			(net "GND")
			(clearance 0.0508)
			(thermal_gap 0.0508)
		)
		(pad "P8" thru_hole circle
			(at 0 17.78)
			(size 1.1684 1.1684)
			(drill 0.762)
			(layers "*.Cu" "*.Mask")
			(remove_unused_layers no)
			(net "GND")
			(clearance 0.0508)
			(thermal_gap 0.0508)
		)
		(pad "P9" thru_hole circle
			(at 0 20.32)
			(size 1.1684 1.1684)
			(drill 0.762)
			(layers "*.Cu" "*.Mask")
			(remove_unused_layers no)
			(net "P12V")
			(clearance 0.0508)
			(thermal_gap 0.0508)
		)
		(pad "P10" thru_hole circle
			(at 0 22.86)
			(size 1.1684 1.1684)
			(drill 0.762)
			(layers "*.Cu" "*.Mask")
			(remove_unused_layers no)
			(net "P12V")
			(clearance 0.0508)
			(thermal_gap 0.0508)
		)
		(pad "P11" thru_hole circle
			(at 0 25.4)
			(size 1.1684 1.1684)
			(drill 0.762)
			(layers "*.Cu" "*.Mask")
			(remove_unused_layers no)
			(net "P12V")
			(clearance 0.0508)
			(thermal_gap 0.0508)
		)
		(pad "P12" thru_hole circle
			(at 0 27.94)
			(size 1.1684 1.1684)
			(drill 0.762)
			(layers "*.Cu" "*.Mask")
			(remove_unused_layers no)
			(net "P12V")
			(clearance 0.0508)
			(thermal_gap 0.0508)
		)
		(pad "P13" thru_hole circle
			(at 0 30.48)
			(size 1.1684 1.1684)
			(drill 0.762)
			(layers "*.Cu" "*.Mask")
			(remove_unused_layers no)
			(net "P12V")
			(clearance 0.0508)
			(thermal_gap 0.0508)
		)
		(pad "P14" thru_hole circle
			(at 0 33.02)
			(size 1.1684 1.1684)
			(drill 0.762)
			(layers "*.Cu" "*.Mask")
			(remove_unused_layers no)
			(net "P12V")
			(clearance 0.0508)
			(thermal_gap 0.0508)
		)
		(pad "P15" thru_hole circle
			(at 0 35.56)
			(size 1.1684 1.1684)
			(drill 0.762)
			(layers "*.Cu" "*.Mask")
			(remove_unused_layers no)
			(net "P12V")
			(clearance 0.0508)
			(thermal_gap 0.0508)
		)
		(pad "P16" thru_hole circle
			(at 0 38.1)
			(size 1.1684 1.1684)
			(drill 0.762)
			(layers "*.Cu" "*.Mask")
			(remove_unused_layers no)
			(net "P12V")
			(clearance 0.0508)
			(thermal_gap 0.0508)
		)
		(pad "P17" thru_hole circle
			(at -2.70002 38.1)
			(size 1.1684 1.1684)
			(drill 0.762)
			(layers "*.Cu" "*.Mask")
			(remove_unused_layers no)
			(net "P12V")
			(clearance 0.0508)
			(thermal_gap 0.0508)
		)
		(pad "P18" thru_hole circle
			(at -2.70002 35.56)
			(size 1.1684 1.1684)
			(drill 0.762)
			(layers "*.Cu" "*.Mask")
			(remove_unused_layers no)
			(net "P12V")
			(clearance 0.0508)
			(thermal_gap 0.0508)
		)
		(pad "P19" thru_hole circle
			(at -2.70002 33.02)
			(size 1.1684 1.1684)
			(drill 0.762)
			(layers "*.Cu" "*.Mask")
			(remove_unused_layers no)
			(net "P12V")
			(clearance 0.0508)
			(thermal_gap 0.0508)
		)
		(pad "P20" thru_hole circle
			(at -2.70002 30.48)
			(size 1.1684 1.1684)
			(drill 0.762)
			(layers "*.Cu" "*.Mask")
			(remove_unused_layers no)
			(net "P12V")
			(clearance 0.0508)
			(thermal_gap 0.0508)
		)
		(pad "P21" thru_hole circle
			(at -2.70002 27.94)
			(size 1.1684 1.1684)
			(drill 0.762)
			(layers "*.Cu" "*.Mask")
			(remove_unused_layers no)
			(net "P12V")
			(clearance 0.0508)
			(thermal_gap 0.0508)
		)
		(pad "P22" thru_hole circle
			(at -2.70002 25.4)
			(size 1.1684 1.1684)
			(drill 0.762)
			(layers "*.Cu" "*.Mask")
			(remove_unused_layers no)
			(net "P12V")
			(clearance 0.0508)
			(thermal_gap 0.0508)
		)
		(pad "P23" thru_hole circle
			(at -2.70002 22.86)
			(size 1.1684 1.1684)
			(drill 0.762)
			(layers "*.Cu" "*.Mask")
			(remove_unused_layers no)
			(net "P12V")
			(clearance 0.0508)
			(thermal_gap 0.0508)
		)
		(pad "P24" thru_hole circle
			(at -2.70002 20.32)
			(size 1.1684 1.1684)
			(drill 0.762)
			(layers "*.Cu" "*.Mask")
			(remove_unused_layers no)
			(net "P12V")
			(clearance 0.0508)
			(thermal_gap 0.0508)
		)
		(pad "P25" thru_hole circle
			(at -2.70002 17.78)
			(size 1.1684 1.1684)
			(drill 0.762)
			(layers "*.Cu" "*.Mask")
			(remove_unused_layers no)
			(net "GND")
			(clearance 0.0508)
			(thermal_gap 0.0508)
		)
		(pad "P26" thru_hole circle
			(at -2.70002 15.24)
			(size 1.1684 1.1684)
			(drill 0.762)
			(layers "*.Cu" "*.Mask")
			(remove_unused_layers no)
			(net "GND")
			(clearance 0.0508)
			(thermal_gap 0.0508)
		)
		(pad "P27" thru_hole circle
			(at -2.70002 12.7)
			(size 1.1684 1.1684)
			(drill 0.762)
			(layers "*.Cu" "*.Mask")
			(remove_unused_layers no)
			(net "GND")
			(clearance 0.0508)
			(thermal_gap 0.0508)
		)
		(pad "P28" thru_hole circle
			(at -2.70002 10.16)
			(size 1.1684 1.1684)
			(drill 0.762)
			(layers "*.Cu" "*.Mask")
			(remove_unused_layers no)
			(net "GND")
			(clearance 0.0508)
			(thermal_gap 0.0508)
		)
		(pad "P29" thru_hole circle
			(at -2.70002 7.62)
			(size 1.1684 1.1684)
			(drill 0.762)
			(layers "*.Cu" "*.Mask")
			(remove_unused_layers no)
			(net "GND")
			(clearance 0.0508)
			(thermal_gap 0.0508)
		)
		(pad "P30" thru_hole circle
			(at -2.70002 5.08)
			(size 1.1684 1.1684)
			(drill 0.762)
			(layers "*.Cu" "*.Mask")
			(remove_unused_layers no)
			(net "GND")
			(clearance 0.0508)
			(thermal_gap 0.0508)
		)
		(pad "P31" thru_hole circle
			(at -2.70002 2.54)
			(size 1.1684 1.1684)
			(drill 0.762)
			(layers "*.Cu" "*.Mask")
			(remove_unused_layers no)
			(net "GND")
			(clearance 0.0508)
			(thermal_gap 0.0508)
		)
		(pad "P32" thru_hole circle
			(at -2.70002 0)
			(size 1.1684 1.1684)
			(drill 0.762)
			(layers "*.Cu" "*.Mask")
			(remove_unused_layers no)
			(net "GND")
			(clearance 0.0508)
			(thermal_gap 0.0508)
		)
		(pad "S1" thru_hole circle
			(at 0.55499 41.60012)
			(size 1.1684 1.1684)
			(drill 0.762)
			(layers "*.Cu" "*.Mask")
			(remove_unused_layers no)
			(net "T11_BLAD1_TXD")
			(clearance 0.0508)
			(thermal_gap 0.0508)
		)
		(pad "S2" thru_hole circle
			(at -0.71501 42.87012)
			(size 1.1684 1.1684)
			(drill 0.762)
			(layers "*.Cu" "*.Mask")
			(remove_unused_layers no)
			(net "T11_BLAD1_RXD")
			(clearance 0.0508)
			(thermal_gap 0.0508)
		)
		(pad "S3" thru_hole circle
			(at 0.55499 44.14012)
			(size 1.1684 1.1684)
			(drill 0.762)
			(layers "*.Cu" "*.Mask")
			(remove_unused_layers no)
			(net "T11_BLAD1_EN")
			(clearance 0.0508)
			(thermal_gap 0.0508)
		)
		(pad "S4" thru_hole circle
			(at -0.71501 45.41012)
			(size 1.1684 1.1684)
			(drill 0.762)
			(layers "*.Cu" "*.Mask")
			(remove_unused_layers no)
			(net "T11_BLAD2_EN")
			(clearance 0.0508)
			(thermal_gap 0.0508)
		)
		(pad "S5" thru_hole circle
			(at 0.55499 46.68012)
			(size 1.1684 1.1684)
			(drill 0.762)
			(layers "*.Cu" "*.Mask")
			(remove_unused_layers no)
			(net "T11_BLAD2_TXD")
			(clearance 0.0508)
			(thermal_gap 0.0508)
		)
		(pad "S6" thru_hole circle
			(at -0.71501 47.95012)
			(size 1.1684 1.1684)
			(drill 0.762)
			(layers "*.Cu" "*.Mask")
			(remove_unused_layers no)
			(net "T11_BLAD2_RXD")
			(clearance 0.0508)
			(thermal_gap 0.0508)
		)
		(pad "S7" thru_hole circle
			(at -3.25501 47.95012)
			(size 1.1684 1.1684)
			(drill 0.762)
			(layers "*.Cu" "*.Mask")
			(remove_unused_layers no)
			(net "T11_BLAD4_RXD")
			(clearance 0.0508)
			(thermal_gap 0.0508)
		)
		(pad "S8" thru_hole circle
			(at -1.98501 46.68012)
			(size 1.1684 1.1684)
			(drill 0.762)
			(layers "*.Cu" "*.Mask")
			(remove_unused_layers no)
			(net "T11_BLAD4_TXD")
			(clearance 0.0508)
			(thermal_gap 0.0508)
		)
		(pad "S9" thru_hole circle
			(at -3.25501 45.41012)
			(size 1.1684 1.1684)
			(drill 0.762)
			(layers "*.Cu" "*.Mask")
			(remove_unused_layers no)
			(net "T11_BLAD4_EN")
			(clearance 0.0508)
			(thermal_gap 0.0508)
		)
		(pad "S10" thru_hole circle
			(at -1.98501 44.14012)
			(size 1.1684 1.1684)
			(drill 0.762)
			(layers "*.Cu" "*.Mask")
			(remove_unused_layers no)
			(net "T11_BLAD3_EN")
			(clearance 0.0508)
			(thermal_gap 0.0508)
		)
		(pad "S11" thru_hole circle
			(at -3.25501 42.87012)
			(size 1.1684 1.1684)
			(drill 0.762)
			(layers "*.Cu" "*.Mask")
			(remove_unused_layers no)
			(net "T11_BLAD3_RXD")
			(clearance 0.0508)
			(thermal_gap 0.0508)
		)
		(pad "S12" thru_hole circle
			(at -1.98501 41.60012)
			(size 1.1684 1.1684)
			(drill 0.762)
			(layers "*.Cu" "*.Mask")
			(remove_unused_layers no)
			(net "T11_BLAD3_TXD")
			(clearance 0.0508)
			(thermal_gap 0.0508)
		)
	)
)
